# BASEBOARD_FAB2 (Tioga Pass) — schematic netlist excerpt (pin names and nets, part order shuffled) for the footprints in the layout excerpt that follows; sources: Cadence DE-HDL packaged netlist, KiCad conversion of Wiwynn_Tioga_Pass_MB.brd

EU4C1  IR354XX  IR35412 IC  pkg SM  page 205
  VOS  = PVSA_CPU0
  LGND  = GND
  VCC  = VR_PVSA_CPU0_VCIN
  VDRV  = P5V_STBY
  PGND(0)  = GND
  GL(0)  = TP_PVSA_CPU0_GL_0
  PGND(1)  = GND
  SW  = VR_PVSA_CPU0_PHASE_SW
  VIN(0)  = VR_FET_SW_P12V_STBY_PVCCIN_CPU0
  VIN(1)  = VR_FET_SW_P12V_STBY_PVCCIN_CPU0
  NC  = NC
  PHASE  = VR_PVSA_CPU0_PHASE
  BOOST  = VR_PVSA_CPU0_BOOT_R
  PWM  = VR_PVSA_CPU0_PWM
  EN  = P5V_STBY
  TOUT_FLT  = A_TSENSE_PVSA_CPU0
  OCSET  = VR_PVSA_CPU0_OCSET
  IOUT  = ISENSE_PVSA_CPU0_IMON
  REFIN  = VR_PVSA_CPU0_BIREF1
  PGND(2)  = GND
  GL(1)  = TP_PVSA_CPU0_GL_1

C3D21  CAP_A  22.0UF 4V 20% X6S  pkg 0603V  page 76 : A = PVCCMCP_CPU1 ; B = GND

(kicad_pcb
	(version 20260206)
	(generator "pcbnew")
	(generator_version "10.0")
	(general
		(thickness 1.6)
		(legacy_teardrops no)
	)
	(paper "A4")
	(title_block
		(title "Wiwynn_Tioga_Pass_MB.brd")
		(comment 1 "Tioga Pass / footprints 2083-2084 of 4770")
	)
	(layers
		(0 "F.Cu" signal "TOP")
		(4 "In1.Cu" signal "L2GND")
		(6 "In2.Cu" signal "L3")
		(8 "In3.Cu" signal "L4GND")
		(10 "In4.Cu" signal "L5")
		(12 "In5.Cu" signal "L6GND")
		(14 "In6.Cu" signal "L7VCC")
		(16 "In7.Cu" signal "L8VCC")
		(18 "In8.Cu" signal "L9GND")
		(20 "In9.Cu" signal "L10")
		(22 "In10.Cu" signal "L11GND")
		(24 "In11.Cu" signal "L12")
		(26 "In12.Cu" signal "L13GND")
		(2 "B.Cu" signal "BOTTOM")
		(9 "F.Adhes" user "F.Adhesive")
		(11 "B.Adhes" user "B.Adhesive")
		(13 "F.Paste" user "Package Geometry/Pastemask Top")
		(15 "B.Paste" user "Package Geometry/Pastemask Bottom")
		(5 "F.SilkS" user "Ref Des/Silkscreen Top")
		(7 "B.SilkS" user "Ref Des/Silkscreen Bottom")
		(1 "F.Mask" user "Board Geometry/Soldermask Top")
		(3 "B.Mask" user "Board Geometry/Soldermask Bottom")
		(17 "Dwgs.User" user "User.Drawings")
		(19 "Cmts.User" user "User.Comments")
		(21 "Eco1.User" user "User.Eco1")
		(23 "Eco2.User" user "User.Eco2")
		(25 "Edge.Cuts" user "Board Geometry/Outline")
		(27 "Margin" user)
		(31 "F.CrtYd" user "Package Geometry/Place Bound Top")
		(29 "B.CrtYd" user "Package Geometry/Place Bound Bottom")
		(35 "F.Fab" user "Ref Des/Assembly Top")
		(33 "B.Fab" user "Ref Des/Assembly Bottom")
	)
	(footprint ""
		(layer "F.Cu")
		(at 198.912734 -97.679764 90)
		(property "Reference" "EU4C1"
			(at 3.893566 -0.538734 0)
			(unlocked yes)
			(layer "F.SilkS")
			(effects
				(font
					(size 0.7874 0.5842)
					(thickness 0.1524)
				)
			)
		)
		(property "Value" ""
			(at 0 0 90)
			(layer "F.Fab")
			(effects
				(font
					(size 1.27 1.27)
				)
			)
		)
		(duplicate_pad_numbers_are_jumpers no)
		(fp_line
			(start 2.9718 -3.5052)
			(end 2.9718 3.429)
			(stroke
				(width 0.1524)
				(type default)
			)
			(layer "F.SilkS")
		)
		(fp_line
			(start -3.0099 -3.5052)
			(end 2.9718 -3.5052)
			(stroke
				(width 0.1524)
				(type default)
			)
			(layer "F.SilkS")
		)
		(fp_line
			(start 2.9718 3.429)
			(end -3.0099 3.429)
			(stroke
				(width 0.1524)
				(type default)
			)
			(layer "F.SilkS")
		)
		(fp_line
			(start -3.0099 3.429)
			(end -3.0099 -3.5052)
			(stroke
				(width 0.1524)
				(type default)
			)
			(layer "F.SilkS")
		)
		(fp_circle
			(center -3.057398 -2.678684)
			(end -3.057398 -2.551684)
			(stroke
				(width 0.254)
				(type default)
			)
			(fill no)
			(layer "F.SilkS")
		)
		(fp_poly
			(pts
				(xy -2.9972 -3.4925) (xy -2.9972 -2.6924) (xy -2.1971 -3.4925)
			)
			(stroke
				(width 0)
				(type default)
			)
			(fill yes)
			(layer "F.SilkS")
		)
		(fp_poly
			(pts
				(xy -2.549906 -3.050032) (xy -2.549906 3.050032) (xy 2.549906 3.050032) (xy 2.549906 -3.050032)
			)
			(stroke
				(width 0)
				(type default)
			)
			(fill no)
			(layer "F.CrtYd")
		)
		(fp_line
			(start 2.549906 -3.050032)
			(end 2.549906 3.050032)
			(stroke
				(width 0.1)
				(type default)
			)
			(layer "F.Fab")
		)
		(fp_line
			(start -2.549906 -3.050032)
			(end 2.549906 -3.050032)
			(stroke
				(width 0.1)
				(type default)
			)
			(layer "F.Fab")
		)
		(fp_line
			(start 2.549906 3.050032)
			(end -2.549906 3.050032)
			(stroke
				(width 0.1)
				(type default)
			)
			(layer "F.Fab")
		)
		(fp_line
			(start -2.549906 3.050032)
			(end -2.549906 -3.050032)
			(stroke
				(width 0.1)
				(type default)
			)
			(layer "F.Fab")
		)
		(fp_circle
			(center -3.057398 -2.678684)
			(end -3.057398 -2.551684)
			(stroke
				(width 0.254)
				(type default)
			)
			(fill no)
			(layer "F.Fab")
		)
		(pad "1" smd rect
			(at -2.39522 -2.279904 90)
			(size 0.7112 0.254)
			(layers "F.Cu" "F.Mask" "F.Paste")
			(net "PVSA_CPU0")
		)
		(pad "2" smd rect
			(at -2.39522 -1.83007 90)
			(size 0.7112 0.254)
			(layers "F.Cu" "F.Mask" "F.Paste")
			(net "GND")
		)
		(pad "3" smd rect
			(at -2.39522 -1.379982 90)
			(size 0.7112 0.254)
			(layers "F.Cu" "F.Mask" "F.Paste")
			(net "VR_PVSA_CPU0_VCIN")
		)
		(pad "4" smd rect
			(at -2.39522 -0.929894 90)
			(size 0.7112 0.254)
			(layers "F.Cu" "F.Mask" "F.Paste")
			(net "P5V_STBY")
		)
		(pad "5" smd rect
			(at -2.39522 -0.48006 90)
			(size 0.7112 0.254)
			(layers "F.Cu" "F.Mask" "F.Paste")
			(net "GND")
		)
		(pad "6" smd rect
			(at -2.39522 -0.029972 90)
			(size 0.7112 0.254)
			(layers "F.Cu" "F.Mask" "F.Paste")
			(net "TP_PVSA_CPU0_GL_0")
		)
		(pad "7" smd custom
			(at 0.016764 1.145032 90)
			(size 0.53975 0.53975)
			(layers "F.Cu" "F.Mask" "F.Paste")
			(net "GND")
			(options
				(clearance outline)
				(anchor circle)
			)
			(primitives
				(gr_poly
					(pts
						(xy -2.7051 1.0795) (xy -2.7051 -0.3683) (xy -0.9271 -0.3683) (xy -0.9271 -1.0795) (xy 2.7051 -1.0795)
						(xy 2.7051 1.0795)
					)
					(width 0)
					(fill yes)
				)
			)
		)
		(pad "10" smd rect
			(at -0.008382 2.874772 90)
			(size 4.3434 0.6096)
			(layers "F.Cu" "F.Mask" "F.Paste")
			(net "VR_PVSA_CPU0_PHASE_SW")
		)
		(pad "25" smd rect
			(at 1.548384 -1.283208 90)
			(size 2.3368 2.0066)
			(layers "F.Cu" "F.Mask" "F.Paste")
			(net "VR_FET_SW_P12V_STBY_PVCCIN_CPU0")
		)
		(pad "30" smd rect
			(at 2.050034 -2.895092 90)
			(size 0.254 0.7112)
			(layers "F.Cu" "F.Mask" "F.Paste")
			(net "VR_FET_SW_P12V_STBY_PVCCIN_CPU0")
		)
		(pad "31" smd rect
			(at 1.599946 -2.895092 90)
			(size 0.254 0.7112)
			(layers "F.Cu" "F.Mask" "F.Paste")
			(net "Net_375")
		)
		(pad "32" smd rect
			(at 1.150112 -2.895092 90)
			(size 0.254 0.7112)
			(layers "F.Cu" "F.Mask" "F.Paste")
			(net "VR_PVSA_CPU0_PHASE")
		)
		(pad "33" smd rect
			(at 0.700024 -2.895092 90)
			(size 0.254 0.7112)
			(layers "F.Cu" "F.Mask" "F.Paste")
			(net "VR_PVSA_CPU0_BOOT_R")
		)
		(pad "34" smd rect
			(at 0.249936 -2.895092 90)
			(size 0.254 0.7112)
			(layers "F.Cu" "F.Mask" "F.Paste")
			(net "VR_PVSA_CPU0_PWM")
		)
		(pad "35" smd rect
			(at -0.199898 -2.895092 90)
			(size 0.254 0.7112)
			(layers "F.Cu" "F.Mask" "F.Paste")
			(net "P5V_STBY")
		)
		(pad "36" smd rect
			(at -0.649986 -2.895092 90)
			(size 0.254 0.7112)
			(layers "F.Cu" "F.Mask" "F.Paste")
			(net "A_TSENSE_PVSA_CPU0")
		)
		(pad "37" smd rect
			(at -1.100074 -2.895092 90)
			(size 0.254 0.7112)
			(layers "F.Cu" "F.Mask" "F.Paste")
			(net "VR_PVSA_CPU0_OCSET")
		)
		(pad "38" smd rect
			(at -1.549908 -2.895092 90)
			(size 0.254 0.7112)
			(layers "F.Cu" "F.Mask" "F.Paste")
			(net "ISENSE_PVSA_CPU0_IMON")
		)
		(pad "39" smd rect
			(at -1.999996 -2.895092 90)
			(size 0.254 0.7112)
			(layers "F.Cu" "F.Mask" "F.Paste")
			(net "VR_PVSA_CPU0_BIREF1")
		)
		(pad "40" smd rect
			(at -0.871728 -1.283208 90)
			(size 1.8034 2.0066)
			(layers "F.Cu" "F.Mask" "F.Paste")
			(net "GND")
		)
		(pad "41" smd rect
			(at -1.533906 0.247904 90)
			(size 0.508 0.3556)
			(layers "F.Cu" "F.Mask" "F.Paste")
			(net "TP_PVSA_CPU0_GL_1")
		)
	)
	(footprint ""
		(layer "F.Cu")
		(at 106.89844 -73.279)
		(property "Reference" "C3D21"
			(at 0 0 0)
			(layer "F.SilkS")
			(hide yes)
			(effects
				(font
					(size 1.27 1.27)
				)
			)
		)
		(property "Value" ""
			(at 0 0 0)
			(layer "F.Fab")
			(effects
				(font
					(size 1.27 1.27)
				)
			)
		)
		(duplicate_pad_numbers_are_jumpers no)
		(fp_poly
			(pts
				(xy -0.4953 -0.2032) (xy 0.4953 -0.2032) (xy 0.4953 1.6002) (xy -0.4953 1.6002)
			)
			(stroke
				(width 0)
				(type default)
			)
			(fill no)
			(layer "F.CrtYd")
		)
		(fp_line
			(start -0.4953 -0.2032)
			(end 0.4953 -0.2032)
			(stroke
				(width 0.1)
				(type default)
			)
			(layer "F.Fab")
		)
		(fp_line
			(start -0.4953 1.6002)
			(end -0.4953 -0.2032)
			(stroke
				(width 0.1)
				(type default)
			)
			(layer "F.Fab")
		)
		(fp_line
			(start 0.4953 -0.2032)
			(end 0.4953 1.6002)
			(stroke
				(width 0.1)
				(type default)
			)
			(layer "F.Fab")
		)
		(fp_line
			(start 0.4953 1.6002)
			(end -0.4953 1.6002)
			(stroke
				(width 0.1)
				(type default)
			)
			(layer "F.Fab")
		)
		(pad "1" smd rect
			(at 0 0)
			(size 0.762 0.889)
			(layers "F.Cu" "F.Mask" "F.Paste")
			(net "PVCCMCP_CPU1")
		)
		(pad "2" smd rect
			(at 0 1.397)
			(size 0.762 0.889)
			(layers "F.Cu" "F.Mask" "F.Paste")
			(net "GND")
		)
		(zone
			(layer "F.Cu")
			(hatch none 0.5)
			(connect_pads
				(clearance 0)
			)
			(min_thickness 0.25)
			(keepout
				(tracks not_allowed)
				(vias allowed)
				(pads allowed)
				(copperpour not_allowed)
				(footprints allowed)
			)
			(placement
				(enabled no)
				(sheetname "")
			)
			(fill
				(thermal_gap 0.5)
				(thermal_bridge_width 0.5)
				(island_removal_mode 0)
			)
			(polygon
				(pts
					(xy 106.51744 -72.8345) (xy 107.27944 -72.8345) (xy 107.27944 -72.3265) (xy 106.51744 -72.3265)
				)
			)
		)
	)
)
